(kicad_pcb
	(version 20260206)
	(generator "pcbnew")
	(generator_version "10.0")
	(general
		(thickness 1.6)
		(legacy_teardrops no)
	)
	(paper "A4")
	(title_block
		(title "04192023_DAF0TMB3IC0_F0TG_MB_C_brd_V02_OCP.brd")
		(comment 1 "Grand Teton / footprints 4052-4057 of 8354")
	)
	(layers
		(0 "F.Cu" signal "TOP")
		(4 "In1.Cu" signal "GND")
		(6 "In2.Cu" signal "IN1")
		(8 "In3.Cu" signal "GND1")
		(10 "In4.Cu" signal "IN2")
		(12 "In5.Cu" signal "GND2")
		(14 "In6.Cu" signal "IN3")
		(16 "In7.Cu" signal "GND3")
		(18 "In8.Cu" signal "VCC")
		(20 "In9.Cu" signal "VCC1")
		(22 "In10.Cu" signal "GND4")
		(24 "In11.Cu" signal "IN4")
		(26 "In12.Cu" signal "GND5")
		(28 "In13.Cu" signal "IN5")
		(30 "In14.Cu" signal "GND6")
		(32 "In15.Cu" signal "IN6")
		(34 "In16.Cu" signal "GND7")
		(2 "B.Cu" signal "BOTTOM")
		(9 "F.Adhes" user "F.Adhesive")
		(11 "B.Adhes" user "B.Adhesive")
		(13 "F.Paste" user "Package Geometry/Pastemask Top")
		(15 "B.Paste" user "Package Geometry/Pastemask Bottom")
		(5 "F.SilkS" user "Ref Des/Silkscreen Top")
		(7 "B.SilkS" user "Ref Des/Silkscreen Bottom")
		(1 "F.Mask" user "Board Geometry/Soldermask Top")
		(3 "B.Mask" user "Board Geometry/Soldermask Bottom")
		(17 "Dwgs.User" user "User.Drawings")
		(19 "Cmts.User" user "User.Comments")
		(21 "Eco1.User" user "User.Eco1")
		(23 "Eco2.User" user "User.Eco2")
		(25 "Edge.Cuts" user "Board Geometry/Outline")
		(27 "Margin" user)
		(31 "F.CrtYd" user "Package Geometry/Place Bound Top")
		(29 "B.CrtYd" user "Package Geometry/Place Bound Bottom")
		(35 "F.Fab" user "Ref Des/Assembly Top")
		(33 "B.Fab" user "Ref Des/Assembly Bottom")
	)
	(footprint ""
		(layer "F.Cu")
		(at 20.575524 -405.868378 90)
		(property "Reference" "R6861"
			(at 0 0 90)
			(layer "F.SilkS")
			(hide yes)
			(effects
				(font
					(size 1.27 1.27)
				)
			)
		)
		(property "Value" ""
			(at 0 0 90)
			(layer "F.Fab")
			(effects
				(font
					(size 1.27 1.27)
				)
			)
		)
		(duplicate_pad_numbers_are_jumpers no)
		(fp_line
			(start 0.7874 -0.4064)
			(end 0.7874 0.4064)
			(stroke
				(width 0.1524)
				(type default)
			)
			(layer "F.SilkS")
		)
		(fp_line
			(start -0.7874 -0.4064)
			(end 0.7874 -0.4064)
			(stroke
				(width 0.1524)
				(type default)
			)
			(layer "F.SilkS")
		)
		(fp_line
			(start 0.7874 0.4064)
			(end -0.7874 0.4064)
			(stroke
				(width 0.1524)
				(type default)
			)
			(layer "F.SilkS")
		)
		(fp_line
			(start -0.7874 0.4064)
			(end -0.7874 -0.4064)
			(stroke
				(width 0.1524)
				(type default)
			)
			(layer "F.SilkS")
		)
		(fp_line
			(start -0.12065 -0.305054)
			(end -0.12065 -0.2794)
			(stroke
				(width 0.1)
				(type default)
			)
			(layer "F.Fab")
		)
		(fp_line
			(start -0.67945 -0.305054)
			(end -0.12065 -0.305054)
			(stroke
				(width 0.1)
				(type default)
			)
			(layer "F.Fab")
		)
		(fp_line
			(start 0.67945 -0.3048)
			(end 0.67945 0.3048)
			(stroke
				(width 0.1)
				(type default)
			)
			(layer "F.Fab")
		)
		(fp_line
			(start 0.12065 -0.3048)
			(end 0.67945 -0.3048)
			(stroke
				(width 0.1)
				(type default)
			)
			(layer "F.Fab")
		)
		(fp_line
			(start 0.12065 -0.2794)
			(end 0.12065 -0.3048)
			(stroke
				(width 0.1)
				(type default)
			)
			(layer "F.Fab")
		)
		(fp_line
			(start -0.12065 -0.2794)
			(end 0.12065 -0.2794)
			(stroke
				(width 0.1)
				(type default)
			)
			(layer "F.Fab")
		)
		(fp_line
			(start 0.120396 0.2794)
			(end -0.12065 0.2794)
			(stroke
				(width 0.1)
				(type default)
			)
			(layer "F.Fab")
		)
		(fp_line
			(start -0.12065 0.2794)
			(end -0.12065 0.3048)
			(stroke
				(width 0.1)
				(type default)
			)
			(layer "F.Fab")
		)
		(fp_line
			(start 0.67945 0.3048)
			(end 0.120396 0.3048)
			(stroke
				(width 0.1)
				(type default)
			)
			(layer "F.Fab")
		)
		(fp_line
			(start 0.120396 0.3048)
			(end 0.120396 0.2794)
			(stroke
				(width 0.1)
				(type default)
			)
			(layer "F.Fab")
		)
		(fp_line
			(start -0.12065 0.3048)
			(end -0.67945 0.3048)
			(stroke
				(width 0.1)
				(type default)
			)
			(layer "F.Fab")
		)
		(fp_line
			(start -0.67945 0.3048)
			(end -0.67945 -0.305054)
			(stroke
				(width 0.1)
				(type default)
			)
			(layer "F.Fab")
		)
		(pad "1" smd circle
			(at -0.40005 0 90)
			(size 0 0)
			(layers "F.Cu" "F.Mask" "F.Paste")
			(net "P1V8_AUX")
		)
		(pad "2" smd circle
			(at 0.40005 0 90)
			(size 0 0)
			(layers "F.Cu" "F.Mask" "F.Paste")
			(net "PWRGD_P0V9_RETIMER_CPU1_R")
		)
	)
	(footprint ""
		(layer "F.Cu")
		(at 73.189084 -408.517344 -90)
		(property "Reference" "C6645"
			(at 0 0 270)
			(layer "F.SilkS")
			(hide yes)
			(effects
				(font
					(size 1.27 1.27)
				)
			)
		)
		(property "Value" ""
			(at 0 0 270)
			(layer "F.Fab")
			(effects
				(font
					(size 1.27 1.27)
				)
			)
		)
		(duplicate_pad_numbers_are_jumpers no)
		(fp_line
			(start -0.299974 0.150114)
			(end -0.299974 -0.150114)
			(stroke
				(width 0.1)
				(type default)
			)
			(layer "F.Fab")
		)
		(fp_line
			(start 0.299974 0.150114)
			(end -0.299974 0.150114)
			(stroke
				(width 0.1)
				(type default)
			)
			(layer "F.Fab")
		)
		(fp_line
			(start -0.299974 -0.150114)
			(end 0.299974 -0.150114)
			(stroke
				(width 0.1)
				(type default)
			)
			(layer "F.Fab")
		)
		(fp_line
			(start 0.299974 -0.150114)
			(end 0.299974 0.150114)
			(stroke
				(width 0.1)
				(type default)
			)
			(layer "F.Fab")
		)
		(pad "1" smd rect
			(at -0.2667 0 270)
			(size 0.3048 0.381)
			(layers "F.Cu" "F.Mask" "F.Paste")
			(net "P5E_CPU1_P0_TX_BUF_C_DP<8>")
		)
		(pad "2" smd rect
			(at 0.2667 0 270)
			(size 0.3048 0.381)
			(layers "F.Cu" "F.Mask" "F.Paste")
			(net "P5E_CPU1_P0_TX_BUF_DP<8>")
		)
	)
	(footprint ""
		(layer "F.Cu")
		(at 231.42702 -291.761926)
		(property "Reference" "PU6501"
			(at 1.014476 -3.50774 0)
			(unlocked yes)
			(layer "F.SilkS")
			(effects
				(font
					(size 0.7874 0.5842)
					(thickness 0.1524)
				)
				(justify left)
			)
		)
		(property "Value" ""
			(at 0 0 0)
			(layer "F.Fab")
			(effects
				(font
					(size 1.27 1.27)
				)
			)
		)
		(duplicate_pad_numbers_are_jumpers no)
		(fp_line
			(start -1.549908 -2.050034)
			(end -1.549908 -1.9812)
			(stroke
				(width 0.1524)
				(type default)
			)
			(layer "F.SilkS")
		)
		(fp_line
			(start -1.549908 1.9812)
			(end -1.549908 2.050034)
			(stroke
				(width 0.1524)
				(type default)
			)
			(layer "F.SilkS")
		)
		(fp_line
			(start -1.549908 2.050034)
			(end -0.5842 2.050034)
			(stroke
				(width 0.1524)
				(type default)
			)
			(layer "F.SilkS")
		)
		(fp_line
			(start -0.5842 -2.050034)
			(end -1.549908 -2.050034)
			(stroke
				(width 0.1524)
				(type default)
			)
			(layer "F.SilkS")
		)
		(fp_line
			(start 0 2.050034)
			(end 1.549908 2.050034)
			(stroke
				(width 0.1524)
				(type default)
			)
			(layer "F.SilkS")
		)
		(fp_line
			(start 1.549908 -2.050034)
			(end 0.5842 -2.050034)
			(stroke
				(width 0.1524)
				(type default)
			)
			(layer "F.SilkS")
		)
		(fp_line
			(start 1.549908 -1.9812)
			(end 1.549908 -2.050034)
			(stroke
				(width 0.1524)
				(type default)
			)
			(layer "F.SilkS")
		)
		(fp_line
			(start 1.549908 2.050034)
			(end 1.549908 1.9304)
			(stroke
				(width 0.1524)
				(type default)
			)
			(layer "F.SilkS")
		)
		(fp_poly
			(pts
				(xy -2.9464 -2.208022) (xy -2.9464 -1.192022) (xy -1.9304 -1.700022)
			)
			(stroke
				(width 0)
				(type default)
			)
			(fill yes)
			(layer "F.SilkS")
		)
		(fp_line
			(start -1.549908 -2.050034)
			(end -1.549908 2.050034)
			(stroke
				(width 0.1)
				(type default)
			)
			(layer "F.Fab")
		)
		(fp_line
			(start -1.549908 2.050034)
			(end 1.549908 2.050034)
			(stroke
				(width 0.1)
				(type default)
			)
			(layer "F.Fab")
		)
		(fp_line
			(start 1.549908 -2.050034)
			(end -1.549908 -2.050034)
			(stroke
				(width 0.1)
				(type default)
			)
			(layer "F.Fab")
		)
		(fp_line
			(start 1.549908 2.050034)
			(end 1.549908 -2.050034)
			(stroke
				(width 0.1)
				(type default)
			)
			(layer "F.Fab")
		)
		(fp_poly
			(pts
				(xy -2.9464 -2.208022) (xy -2.9464 -1.192022) (xy -1.9304 -1.700022)
			)
			(stroke
				(width 0)
				(type default)
			)
			(fill yes)
			(layer "F.Fab")
		)
		(pad "1" smd circle
			(at -1.35001 -1.700022)
			(size 0 0)
			(layers "F.Cu" "F.Mask" "F.Paste")
			(net "SW_P1V8_RETIMER_CPU1_BST")
		)
		(pad "2" smd rect
			(at -1.400048 -1.199896 90)
			(size 0.1778 0.8128)
			(layers "F.Cu" "F.Mask" "F.Paste")
			(net "GND")
		)
		(pad "3" smd rect
			(at -1.400048 -0.8001 90)
			(size 0.1778 0.8128)
			(layers "F.Cu" "F.Mask" "F.Paste")
			(net "P1V8_RETIMER_CPU1_CS")
		)
		(pad "4" smd rect
			(at -1.400048 -0.40005 90)
			(size 0.1778 0.8128)
			(layers "F.Cu" "F.Mask" "F.Paste")
			(net "P1V8_RETIMER_CPU1_MODE")
		)
		(pad "5" smd rect
			(at -1.400048 0 90)
			(size 0.1778 0.8128)
			(layers "F.Cu" "F.Mask" "F.Paste")
			(net "P1V8_RETIMER_CPU1_REF")
		)
		(pad "6" smd rect
			(at -1.400048 0.40005 90)
			(size 0.1778 0.8128)
			(layers "F.Cu" "F.Mask" "F.Paste")
			(net "GND")
		)
		(pad "7" smd rect
			(at -1.400048 0.8001 90)
			(size 0.1778 0.8128)
			(layers "F.Cu" "F.Mask" "F.Paste")
			(net "P1V8_RETIMER_CPU1_FB")
		)
		(pad "8" smd rect
			(at -1.400048 1.199896 90)
			(size 0.1778 0.8128)
			(layers "F.Cu" "F.Mask" "F.Paste")
			(net "P1V8_RETIMER_CPU1_EN")
		)
		(pad "9" smd rect
			(at -1.400048 1.700022 90)
			(size 0.3048 0.8128)
			(layers "F.Cu" "F.Mask" "F.Paste")
			(net "PWRGD_P1V8_RETIMER_CPU1")
		)
		(pad "10" smd rect
			(at -0.299974 1.299972)
			(size 0.3048 2.0066)
			(layers "F.Cu" "F.Mask" "F.Paste")
			(net "SW_P12V_AUX_P1V8_RETIMER_CPU1_FLT")
		)
		(pad "11_18" smd circle
			(at 1.175004 0.275082)
			(size 0 0)
			(layers "F.Cu" "F.Mask" "F.Paste")
			(net "GND")
		)
		(pad "19" smd rect
			(at 1.400048 -1.700022 270)
			(size 0.3048 0.8128)
			(layers "F.Cu" "F.Mask" "F.Paste")
			(net "P1V8_RETIMER_CPU1_VCC")
		)
		(pad "20" smd rect
			(at 0.299974 -1.299972)
			(size 0.3048 2.0066)
			(layers "F.Cu" "F.Mask" "F.Paste")
			(net "SW_P1V8_RETIMER_CPU1_SW")
		)
		(pad "21" smd rect
			(at -0.299974 -1.299972)
			(size 0.3048 2.0066)
			(layers "F.Cu" "F.Mask" "F.Paste")
			(net "SW_P12V_AUX_P1V8_RETIMER_CPU1_FLT")
		)
	)
	(footprint ""
		(layer "F.Cu")
		(at 303.999392 -346.866464 -90)
		(property "Reference" "PC150_1"
			(at 0 0 270)
			(layer "F.SilkS")
			(hide yes)
			(effects
				(font
					(size 1.27 1.27)
				)
			)
		)
		(property "Value" ""
			(at 0 0 270)
			(layer "F.Fab")
			(effects
				(font
					(size 1.27 1.27)
				)
			)
		)
		(duplicate_pad_numbers_are_jumpers no)
		(fp_line
			(start -0.7874 0.4064)
			(end -0.7874 -0.4064)
			(stroke
				(width 0.1524)
				(type default)
			)
			(layer "F.SilkS")
		)
		(fp_line
			(start 0.7874 0.4064)
			(end -0.7874 0.4064)
			(stroke
				(width 0.1524)
				(type default)
			)
			(layer "F.SilkS")
		)
		(fp_line
			(start -0.7874 -0.4064)
			(end 0.7874 -0.4064)
			(stroke
				(width 0.1524)
				(type default)
			)
			(layer "F.SilkS")
		)
		(fp_line
			(start 0.7874 -0.4064)
			(end 0.7874 0.4064)
			(stroke
				(width 0.1524)
				(type default)
			)
			(layer "F.SilkS")
		)
		(fp_line
			(start -0.67945 0.3048)
			(end -0.67945 -0.305054)
			(stroke
				(width 0.1)
				(type default)
			)
			(layer "F.Fab")
		)
		(fp_line
			(start -0.12065 0.3048)
			(end -0.67945 0.3048)
			(stroke
				(width 0.1)
				(type default)
			)
			(layer "F.Fab")
		)
		(fp_line
			(start 0.120396 0.3048)
			(end 0.120396 0.2794)
			(stroke
				(width 0.1)
				(type default)
			)
			(layer "F.Fab")
		)
		(fp_line
			(start 0.67945 0.3048)
			(end 0.120396 0.3048)
			(stroke
				(width 0.1)
				(type default)
			)
			(layer "F.Fab")
		)
		(fp_line
			(start -0.12065 0.2794)
			(end -0.12065 0.3048)
			(stroke
				(width 0.1)
				(type default)
			)
			(layer "F.Fab")
		)
		(fp_line
			(start 0.120396 0.2794)
			(end -0.12065 0.2794)
			(stroke
				(width 0.1)
				(type default)
			)
			(layer "F.Fab")
		)
		(fp_line
			(start -0.12065 -0.2794)
			(end 0.12065 -0.2794)
			(stroke
				(width 0.1)
				(type default)
			)
			(layer "F.Fab")
		)
		(fp_line
			(start 0.12065 -0.2794)
			(end 0.12065 -0.3048)
			(stroke
				(width 0.1)
				(type default)
			)
			(layer "F.Fab")
		)
		(fp_line
			(start 0.12065 -0.3048)
			(end 0.67945 -0.3048)
			(stroke
				(width 0.1)
				(type default)
			)
			(layer "F.Fab")
		)
		(fp_line
			(start 0.67945 -0.3048)
			(end 0.67945 0.3048)
			(stroke
				(width 0.1)
				(type default)
			)
			(layer "F.Fab")
		)
		(fp_line
			(start -0.67945 -0.305054)
			(end -0.12065 -0.305054)
			(stroke
				(width 0.1)
				(type default)
			)
			(layer "F.Fab")
		)
		(fp_line
			(start -0.12065 -0.305054)
			(end -0.12065 -0.2794)
			(stroke
				(width 0.1)
				(type default)
			)
			(layer "F.Fab")
		)
		(pad "1" smd circle
			(at -0.40005 0 270)
			(size 0 0)
			(layers "F.Cu" "F.Mask" "F.Paste")
			(net "SW_P12V_AUX_PVDDIO_P0_FLT")
		)
		(pad "2" smd circle
			(at 0.40005 0 270)
			(size 0 0)
			(layers "F.Cu" "F.Mask" "F.Paste")
			(net "GND")
		)
	)
	(footprint ""
		(layer "F.Cu")
		(at 418.2237 -166.772082)
		(property "Reference" "PC188"
			(at 0 0 0)
			(layer "F.SilkS")
			(hide yes)
			(effects
				(font
					(size 1.27 1.27)
				)
			)
		)
		(property "Value" ""
			(at 0 0 0)
			(layer "F.Fab")
			(effects
				(font
					(size 1.27 1.27)
				)
			)
		)
		(duplicate_pad_numbers_are_jumpers no)
		(fp_line
			(start -0.7874 -0.4064)
			(end 0.7874 -0.4064)
			(stroke
				(width 0.1524)
				(type default)
			)
			(layer "F.SilkS")
		)
		(fp_line
			(start -0.7874 0.4064)
			(end -0.7874 -0.4064)
			(stroke
				(width 0.1524)
				(type default)
			)
			(layer "F.SilkS")
		)
		(fp_line
			(start 0.7874 -0.4064)
			(end 0.7874 0.4064)
			(stroke
				(width 0.1524)
				(type default)
			)
			(layer "F.SilkS")
		)
		(fp_line
			(start 0.7874 0.4064)
			(end -0.7874 0.4064)
			(stroke
				(width 0.1524)
				(type default)
			)
			(layer "F.SilkS")
		)
		(fp_line
			(start -0.67945 -0.305054)
			(end -0.12065 -0.305054)
			(stroke
				(width 0.1)
				(type default)
			)
			(layer "F.Fab")
		)
		(fp_line
			(start -0.67945 0.3048)
			(end -0.67945 -0.305054)
			(stroke
				(width 0.1)
				(type default)
			)
			(layer "F.Fab")
		)
		(fp_line
			(start -0.12065 -0.305054)
			(end -0.12065 -0.2794)
			(stroke
				(width 0.1)
				(type default)
			)
			(layer "F.Fab")
		)
		(fp_line
			(start -0.12065 -0.2794)
			(end 0.12065 -0.2794)
			(stroke
				(width 0.1)
				(type default)
			)
			(layer "F.Fab")
		)
		(fp_line
			(start -0.12065 0.2794)
			(end -0.12065 0.3048)
			(stroke
				(width 0.1)
				(type default)
			)
			(layer "F.Fab")
		)
		(fp_line
			(start -0.12065 0.3048)
			(end -0.67945 0.3048)
			(stroke
				(width 0.1)
				(type default)
			)
			(layer "F.Fab")
		)
		(fp_line
			(start 0.120396 0.2794)
			(end -0.12065 0.2794)
			(stroke
				(width 0.1)
				(type default)
			)
			(layer "F.Fab")
		)
		(fp_line
			(start 0.120396 0.3048)
			(end 0.120396 0.2794)
			(stroke
				(width 0.1)
				(type default)
			)
			(layer "F.Fab")
		)
		(fp_line
			(start 0.12065 -0.3048)
			(end 0.67945 -0.3048)
			(stroke
				(width 0.1)
				(type default)
			)
			(layer "F.Fab")
		)
		(fp_line
			(start 0.12065 -0.2794)
			(end 0.12065 -0.3048)
			(stroke
				(width 0.1)
				(type default)
			)
			(layer "F.Fab")
		)
		(fp_line
			(start 0.67945 -0.3048)
			(end 0.67945 0.3048)
			(stroke
				(width 0.1)
				(type default)
			)
			(layer "F.Fab")
		)
		(fp_line
			(start 0.67945 0.3048)
			(end 0.120396 0.3048)
			(stroke
				(width 0.1)
				(type default)
			)
			(layer "F.Fab")
		)
		(pad "1" smd circle
			(at -0.40005 0)
			(size 0 0)
			(layers "F.Cu" "F.Mask" "F.Paste")
			(net "SW_PVDDCR_SOC_P0_SW3")
		)
		(pad "2" smd circle
			(at 0.40005 0)
			(size 0 0)
			(layers "F.Cu" "F.Mask" "F.Paste")
			(net "SW_PVDDCR_SOC_P0_SW3_RC")
		)
	)
	(footprint ""
		(layer "F.Cu")
		(at 103.453946 -52.86248 -90)
		(property "Reference" "R6316"
			(at 0 0 270)
			(layer "F.SilkS")
			(hide yes)
			(effects
				(font
					(size 1.27 1.27)
				)
			)
		)
		(property "Value" ""
			(at 0 0 270)
			(layer "F.Fab")
			(effects
				(font
					(size 1.27 1.27)
				)
			)
		)
		(duplicate_pad_numbers_are_jumpers no)
		(fp_line
			(start -0.7874 0.4064)
			(end -0.7874 -0.4064)
			(stroke
				(width 0.1524)
				(type default)
			)
			(layer "F.SilkS")
		)
		(fp_line
			(start 0.7874 0.4064)
			(end -0.7874 0.4064)
			(stroke
				(width 0.1524)
				(type default)
			)
			(layer "F.SilkS")
		)
		(fp_line
			(start -0.7874 -0.4064)
			(end 0.7874 -0.4064)
			(stroke
				(width 0.1524)
				(type default)
			)
			(layer "F.SilkS")
		)
		(fp_line
			(start 0.7874 -0.4064)
			(end 0.7874 0.4064)
			(stroke
				(width 0.1524)
				(type default)
			)
			(layer "F.SilkS")
		)
		(fp_line
			(start -0.67945 0.3048)
			(end -0.67945 -0.305054)
			(stroke
				(width 0.1)
				(type default)
			)
			(layer "F.Fab")
		)
		(fp_line
			(start -0.12065 0.3048)
			(end -0.67945 0.3048)
			(stroke
				(width 0.1)
				(type default)
			)
			(layer "F.Fab")
		)
		(fp_line
			(start 0.120396 0.3048)
			(end 0.120396 0.2794)
			(stroke
				(width 0.1)
				(type default)
			)
			(layer "F.Fab")
		)
		(fp_line
			(start 0.67945 0.3048)
			(end 0.120396 0.3048)
			(stroke
				(width 0.1)
				(type default)
			)
			(layer "F.Fab")
		)
		(fp_line
			(start -0.12065 0.2794)
			(end -0.12065 0.3048)
			(stroke
				(width 0.1)
				(type default)
			)
			(layer "F.Fab")
		)
		(fp_line
			(start 0.120396 0.2794)
			(end -0.12065 0.2794)
			(stroke
				(width 0.1)
				(type default)
			)
			(layer "F.Fab")
		)
		(fp_line
			(start -0.12065 -0.2794)
			(end 0.12065 -0.2794)
			(stroke
				(width 0.1)
				(type default)
			)
			(layer "F.Fab")
		)
		(fp_line
			(start 0.12065 -0.2794)
			(end 0.12065 -0.3048)
			(stroke
				(width 0.1)
				(type default)
			)
			(layer "F.Fab")
		)
		(fp_line
			(start 0.12065 -0.3048)
			(end 0.67945 -0.3048)
			(stroke
				(width 0.1)
				(type default)
			)
			(layer "F.Fab")
		)
		(fp_line
			(start 0.67945 -0.3048)
			(end 0.67945 0.3048)
			(stroke
				(width 0.1)
				(type default)
			)
			(layer "F.Fab")
		)
		(fp_line
			(start -0.67945 -0.305054)
			(end -0.12065 -0.305054)
			(stroke
				(width 0.1)
				(type default)
			)
			(layer "F.Fab")
		)
		(fp_line
			(start -0.12065 -0.305054)
			(end -0.12065 -0.2794)
			(stroke
				(width 0.1)
				(type default)
			)
			(layer "F.Fab")
		)
		(pad "1" smd circle
			(at -0.40005 0 270)
			(size 0 0)
			(layers "F.Cu" "F.Mask" "F.Paste")
			(net "USB_HUB2_TI_USB_VBUS")
		)
		(pad "2" smd circle
			(at 0.40005 0 270)
			(size 0 0)
			(layers "F.Cu" "F.Mask" "F.Paste")
			(net "USB_HUB2_TI_USB_VBUS_MRP_RESET_N")
		)
	)
)
